# S9S_MB_2U (Grand Teton) — schematic netlist excerpt (pin names and nets, part order shuffled) for the footprints in the layout excerpt that follows; sources: Cadence DE-HDL packaged netlist, KiCad conversion of 03242023_DA0F0TMBIJ0_F0T_Motherboard_J_brd_V01_OCP.brd

R4055  Q_RES  1K 1% CHIP  pkg 0402LF  page 225 : A = PD_CPU1_ERRS_U306_DIR ; B = GND
R4594  Q_RES  0 5% CHIP  pkg 0402LF  page 292 : A = SMB_VR_3V3AUX_SCL_R ; B = SMB_CLK_PVCCINFAON_CPU1

(kicad_pcb
	(version 20260206)
	(generator "pcbnew")
	(generator_version "10.0")
	(general
		(thickness 1.6)
		(legacy_teardrops no)
	)
	(paper "A4")
	(title_block
		(title "03242023_DA0F0TMBIJ0_F0T_Motherboard_J_brd_V01_OCP.brd")
		(comment 1 "Grand Teton / footprints 3600-3601 of 6105")
	)
	(layers
		(0 "F.Cu" signal "TOP")
		(4 "In1.Cu" signal "GND")
		(6 "In2.Cu" signal "IN1")
		(8 "In3.Cu" signal "GND1")
		(10 "In4.Cu" signal "IN2")
		(12 "In5.Cu" signal "GND2")
		(14 "In6.Cu" signal "IN3")
		(16 "In7.Cu" signal "GND3")
		(18 "In8.Cu" signal "VCC")
		(20 "In9.Cu" signal "VCC1")
		(22 "In10.Cu" signal "GND4")
		(24 "In11.Cu" signal "IN4")
		(26 "In12.Cu" signal "GND5")
		(28 "In13.Cu" signal "IN5")
		(30 "In14.Cu" signal "GND6")
		(32 "In15.Cu" signal "IN6")
		(34 "In16.Cu" signal "GND7")
		(2 "B.Cu" signal "BOTTOM")
		(9 "F.Adhes" user "F.Adhesive")
		(11 "B.Adhes" user "B.Adhesive")
		(13 "F.Paste" user "Package Geometry/Pastemask Top")
		(15 "B.Paste" user "Package Geometry/Pastemask Bottom")
		(5 "F.SilkS" user "Ref Des/Silkscreen Top")
		(7 "B.SilkS" user "Ref Des/Silkscreen Bottom")
		(1 "F.Mask" user "Board Geometry/Soldermask Top")
		(3 "B.Mask" user "Board Geometry/Soldermask Bottom")
		(17 "Dwgs.User" user "User.Drawings")
		(19 "Cmts.User" user "User.Comments")
		(21 "Eco1.User" user "User.Eco1")
		(23 "Eco2.User" user "User.Eco2")
		(25 "Edge.Cuts" user "Board Geometry/Outline")
		(27 "Margin" user)
		(31 "F.CrtYd" user "Package Geometry/Place Bound Top")
		(29 "B.CrtYd" user "Package Geometry/Place Bound Bottom")
		(35 "F.Fab" user "Ref Des/Assembly Top")
		(33 "B.Fab" user "Ref Des/Assembly Bottom")
	)
	(footprint ""
		(layer "F.Cu")
		(at 144.6022 -104.116378 90)
		(property "Reference" "R4055"
			(at 0 0 90)
			(layer "F.SilkS")
			(hide yes)
			(effects
				(font
					(size 1.27 1.27)
				)
			)
		)
		(property "Value" ""
			(at 0 0 90)
			(layer "F.Fab")
			(effects
				(font
					(size 1.27 1.27)
				)
			)
		)
		(duplicate_pad_numbers_are_jumpers no)
		(fp_line
			(start 0.7874 -0.4064)
			(end 0.7874 0.4064)
			(stroke
				(width 0.1524)
				(type default)
			)
			(layer "F.SilkS")
		)
		(fp_line
			(start -0.7874 -0.4064)
			(end 0.7874 -0.4064)
			(stroke
				(width 0.1524)
				(type default)
			)
			(layer "F.SilkS")
		)
		(fp_line
			(start 0.7874 0.4064)
			(end -0.7874 0.4064)
			(stroke
				(width 0.1524)
				(type default)
			)
			(layer "F.SilkS")
		)
		(fp_line
			(start -0.7874 0.4064)
			(end -0.7874 -0.4064)
			(stroke
				(width 0.1524)
				(type default)
			)
			(layer "F.SilkS")
		)
		(fp_line
			(start -0.12065 -0.305054)
			(end -0.12065 -0.2794)
			(stroke
				(width 0.1)
				(type default)
			)
			(layer "F.Fab")
		)
		(fp_line
			(start -0.67945 -0.305054)
			(end -0.12065 -0.305054)
			(stroke
				(width 0.1)
				(type default)
			)
			(layer "F.Fab")
		)
		(fp_line
			(start 0.67945 -0.3048)
			(end 0.67945 0.3048)
			(stroke
				(width 0.1)
				(type default)
			)
			(layer "F.Fab")
		)
		(fp_line
			(start 0.12065 -0.3048)
			(end 0.67945 -0.3048)
			(stroke
				(width 0.1)
				(type default)
			)
			(layer "F.Fab")
		)
		(fp_line
			(start 0.12065 -0.2794)
			(end 0.12065 -0.3048)
			(stroke
				(width 0.1)
				(type default)
			)
			(layer "F.Fab")
		)
		(fp_line
			(start -0.12065 -0.2794)
			(end 0.12065 -0.2794)
			(stroke
				(width 0.1)
				(type default)
			)
			(layer "F.Fab")
		)
		(fp_line
			(start 0.120396 0.2794)
			(end -0.12065 0.2794)
			(stroke
				(width 0.1)
				(type default)
			)
			(layer "F.Fab")
		)
		(fp_line
			(start -0.12065 0.2794)
			(end -0.12065 0.3048)
			(stroke
				(width 0.1)
				(type default)
			)
			(layer "F.Fab")
		)
		(fp_line
			(start 0.67945 0.3048)
			(end 0.120396 0.3048)
			(stroke
				(width 0.1)
				(type default)
			)
			(layer "F.Fab")
		)
		(fp_line
			(start 0.120396 0.3048)
			(end 0.120396 0.2794)
			(stroke
				(width 0.1)
				(type default)
			)
			(layer "F.Fab")
		)
		(fp_line
			(start -0.12065 0.3048)
			(end -0.67945 0.3048)
			(stroke
				(width 0.1)
				(type default)
			)
			(layer "F.Fab")
		)
		(fp_line
			(start -0.67945 0.3048)
			(end -0.67945 -0.305054)
			(stroke
				(width 0.1)
				(type default)
			)
			(layer "F.Fab")
		)
		(pad "1" smd circle
			(at -0.40005 0 90)
			(size 0 0)
			(layers "F.Cu" "F.Mask" "F.Paste")
			(net "PD_CPU1_ERRS_U306_DIR")
		)
		(pad "2" smd circle
			(at 0.40005 0 90)
			(size 0 0)
			(layers "F.Cu" "F.Mask" "F.Paste")
			(net "GND")
		)
	)
	(footprint ""
		(layer "F.Cu")
		(at 34.291524 -124.99721 90)
		(property "Reference" "R4594"
			(at 0 0 90)
			(layer "F.SilkS")
			(hide yes)
			(effects
				(font
					(size 1.27 1.27)
				)
			)
		)
		(property "Value" ""
			(at 0 0 90)
			(layer "F.Fab")
			(effects
				(font
					(size 1.27 1.27)
				)
			)
		)
		(duplicate_pad_numbers_are_jumpers no)
		(fp_line
			(start 0.7874 -0.4064)
			(end 0.7874 0.4064)
			(stroke
				(width 0.1524)
				(type default)
			)
			(layer "F.SilkS")
		)
		(fp_line
			(start -0.7874 -0.4064)
			(end 0.7874 -0.4064)
			(stroke
				(width 0.1524)
				(type default)
			)
			(layer "F.SilkS")
		)
		(fp_line
			(start 0.7874 0.4064)
			(end -0.7874 0.4064)
			(stroke
				(width 0.1524)
				(type default)
			)
			(layer "F.SilkS")
		)
		(fp_line
			(start -0.7874 0.4064)
			(end -0.7874 -0.4064)
			(stroke
				(width 0.1524)
				(type default)
			)
			(layer "F.SilkS")
		)
		(fp_line
			(start -0.12065 -0.305054)
			(end -0.12065 -0.2794)
			(stroke
				(width 0.1)
				(type default)
			)
			(layer "F.Fab")
		)
		(fp_line
			(start -0.67945 -0.305054)
			(end -0.12065 -0.305054)
			(stroke
				(width 0.1)
				(type default)
			)
			(layer "F.Fab")
		)
		(fp_line
			(start 0.67945 -0.3048)
			(end 0.67945 0.3048)
			(stroke
				(width 0.1)
				(type default)
			)
			(layer "F.Fab")
		)
		(fp_line
			(start 0.12065 -0.3048)
			(end 0.67945 -0.3048)
			(stroke
				(width 0.1)
				(type default)
			)
			(layer "F.Fab")
		)
		(fp_line
			(start 0.12065 -0.2794)
			(end 0.12065 -0.3048)
			(stroke
				(width 0.1)
				(type default)
			)
			(layer "F.Fab")
		)
		(fp_line
			(start -0.12065 -0.2794)
			(end 0.12065 -0.2794)
			(stroke
				(width 0.1)
				(type default)
			)
			(layer "F.Fab")
		)
		(fp_line
			(start 0.120396 0.2794)
			(end -0.12065 0.2794)
			(stroke
				(width 0.1)
				(type default)
			)
			(layer "F.Fab")
		)
		(fp_line
			(start -0.12065 0.2794)
			(end -0.12065 0.3048)
			(stroke
				(width 0.1)
				(type default)
			)
			(layer "F.Fab")
		)
		(fp_line
			(start 0.67945 0.3048)
			(end 0.120396 0.3048)
			(stroke
				(width 0.1)
				(type default)
			)
			(layer "F.Fab")
		)
		(fp_line
			(start 0.120396 0.3048)
			(end 0.120396 0.2794)
			(stroke
				(width 0.1)
				(type default)
			)
			(layer "F.Fab")
		)
		(fp_line
			(start -0.12065 0.3048)
			(end -0.67945 0.3048)
			(stroke
				(width 0.1)
				(type default)
			)
			(layer "F.Fab")
		)
		(fp_line
			(start -0.67945 0.3048)
			(end -0.67945 -0.305054)
			(stroke
				(width 0.1)
				(type default)
			)
			(layer "F.Fab")
		)
		(pad "1" smd circle
			(at -0.40005 0 90)
			(size 0 0)
			(layers "F.Cu" "F.Mask" "F.Paste")
			(net "SMB_VR_3V3AUX_SCL_R")
		)
		(pad "2" smd circle
			(at 0.40005 0 90)
			(size 0 0)
			(layers "F.Cu" "F.Mask" "F.Paste")
			(net "SMB_CLK_PVCCINFAON_CPU1")
		)
	)
)
